# S9S_MB_2U (Grand Teton) — schematic netlist excerpt (pin names and nets, part order shuffled) for the footprints in the layout excerpt that follows; sources: Cadence DE-HDL packaged netlist, KiCad conversion of 03242023_DA0F0TMBIJ0_F0T_Motherboard_J_brd_V01_OCP.brd

R264  Q_RES  240 1% EMPTY  pkg 0402LF  page 119 : A = PVNN_TERM_CPU1 ; B = H_CPU1_BMCINIT_LVC1
R911  Q_RES  240 1% CHIP  pkg 0402LF  page 235 : A = PVNN_TERM_CPU0 ; B = SMB_PEHPCPU0_GTL_R_SDA
C16  Q_CAP  10UF 16V 10% X6S  pkg C0805  page 86 : A = P12V_S3_AUX_CPU0_NVDIMM ; B = GND

(kicad_pcb
	(version 20260206)
	(generator "pcbnew")
	(generator_version "10.0")
	(general
		(thickness 1.6)
		(legacy_teardrops no)
	)
	(paper "A4")
	(title_block
		(title "03242023_DA0F0TMBIJ0_F0T_Motherboard_J_brd_V01_OCP.brd")
		(comment 1 "Grand Teton / footprints 5104-5106 of 6105")
	)
	(layers
		(0 "F.Cu" signal "TOP")
		(4 "In1.Cu" signal "GND")
		(6 "In2.Cu" signal "IN1")
		(8 "In3.Cu" signal "GND1")
		(10 "In4.Cu" signal "IN2")
		(12 "In5.Cu" signal "GND2")
		(14 "In6.Cu" signal "IN3")
		(16 "In7.Cu" signal "GND3")
		(18 "In8.Cu" signal "VCC")
		(20 "In9.Cu" signal "VCC1")
		(22 "In10.Cu" signal "GND4")
		(24 "In11.Cu" signal "IN4")
		(26 "In12.Cu" signal "GND5")
		(28 "In13.Cu" signal "IN5")
		(30 "In14.Cu" signal "GND6")
		(32 "In15.Cu" signal "IN6")
		(34 "In16.Cu" signal "GND7")
		(2 "B.Cu" signal "BOTTOM")
		(9 "F.Adhes" user "F.Adhesive")
		(11 "B.Adhes" user "B.Adhesive")
		(13 "F.Paste" user "Package Geometry/Pastemask Top")
		(15 "B.Paste" user "Package Geometry/Pastemask Bottom")
		(5 "F.SilkS" user "Ref Des/Silkscreen Top")
		(7 "B.SilkS" user "Ref Des/Silkscreen Bottom")
		(1 "F.Mask" user "Board Geometry/Soldermask Top")
		(3 "B.Mask" user "Board Geometry/Soldermask Bottom")
		(17 "Dwgs.User" user "User.Drawings")
		(19 "Cmts.User" user "User.Comments")
		(21 "Eco1.User" user "User.Eco1")
		(23 "Eco2.User" user "User.Eco2")
		(25 "Edge.Cuts" user "Board Geometry/Outline")
		(27 "Margin" user)
		(31 "F.CrtYd" user "Package Geometry/Place Bound Top")
		(29 "B.CrtYd" user "Package Geometry/Place Bound Bottom")
		(35 "F.Fab" user "Ref Des/Assembly Top")
		(33 "B.Fab" user "Ref Des/Assembly Bottom")
	)
	(footprint ""
		(layer "B.Cu")
		(at 71.65848 -183.278018 -90)
		(property "Reference" "R264"
			(at 0 0 90)
			(layer "B.SilkS")
			(hide yes)
			(effects
				(font
					(size 1.27 1.27)
				)
				(justify mirror)
			)
		)
		(property "Value" ""
			(at 0 0 90)
			(layer "B.Fab")
			(effects
				(font
					(size 1.27 1.27)
				)
				(justify mirror)
			)
		)
		(duplicate_pad_numbers_are_jumpers no)
		(fp_line
			(start -0.7874 0.4064)
			(end 0.7874 0.4064)
			(stroke
				(width 0.1524)
				(type default)
			)
			(layer "B.SilkS")
		)
		(fp_line
			(start 0.7874 0.4064)
			(end 0.7874 -0.4064)
			(stroke
				(width 0.1524)
				(type default)
			)
			(layer "B.SilkS")
		)
		(fp_line
			(start -0.7874 -0.4064)
			(end -0.7874 0.4064)
			(stroke
				(width 0.1524)
				(type default)
			)
			(layer "B.SilkS")
		)
		(fp_line
			(start 0.7874 -0.4064)
			(end -0.7874 -0.4064)
			(stroke
				(width 0.1524)
				(type default)
			)
			(layer "B.SilkS")
		)
		(fp_line
			(start -0.67945 0.3048)
			(end -0.120396 0.3048)
			(stroke
				(width 0.1)
				(type default)
			)
			(layer "B.Fab")
		)
		(fp_line
			(start -0.120396 0.3048)
			(end -0.120396 0.2794)
			(stroke
				(width 0.1)
				(type default)
			)
			(layer "B.Fab")
		)
		(fp_line
			(start 0.12065 0.3048)
			(end 0.67945 0.3048)
			(stroke
				(width 0.1)
				(type default)
			)
			(layer "B.Fab")
		)
		(fp_line
			(start 0.67945 0.3048)
			(end 0.67945 -0.305054)
			(stroke
				(width 0.1)
				(type default)
			)
			(layer "B.Fab")
		)
		(fp_line
			(start -0.120396 0.2794)
			(end 0.12065 0.2794)
			(stroke
				(width 0.1)
				(type default)
			)
			(layer "B.Fab")
		)
		(fp_line
			(start 0.12065 0.2794)
			(end 0.12065 0.3048)
			(stroke
				(width 0.1)
				(type default)
			)
			(layer "B.Fab")
		)
		(fp_line
			(start -0.12065 -0.2794)
			(end -0.12065 -0.3048)
			(stroke
				(width 0.1)
				(type default)
			)
			(layer "B.Fab")
		)
		(fp_line
			(start 0.12065 -0.2794)
			(end -0.12065 -0.2794)
			(stroke
				(width 0.1)
				(type default)
			)
			(layer "B.Fab")
		)
		(fp_line
			(start -0.67945 -0.3048)
			(end -0.67945 0.3048)
			(stroke
				(width 0.1)
				(type default)
			)
			(layer "B.Fab")
		)
		(fp_line
			(start -0.12065 -0.3048)
			(end -0.67945 -0.3048)
			(stroke
				(width 0.1)
				(type default)
			)
			(layer "B.Fab")
		)
		(fp_line
			(start 0.12065 -0.305054)
			(end 0.12065 -0.2794)
			(stroke
				(width 0.1)
				(type default)
			)
			(layer "B.Fab")
		)
		(fp_line
			(start 0.67945 -0.305054)
			(end 0.12065 -0.305054)
			(stroke
				(width 0.1)
				(type default)
			)
			(layer "B.Fab")
		)
		(pad "1" smd circle
			(at 0.40005 0 90)
			(size 0 0)
			(layers "B.Cu" "B.Mask" "B.Paste")
			(net "PVNN_TERM_CPU1")
		)
		(pad "2" smd circle
			(at -0.40005 0 90)
			(size 0 0)
			(layers "B.Cu" "B.Mask" "B.Paste")
			(net "H_CPU1_BMCINIT_LVC1")
		)
	)
	(footprint ""
		(layer "B.Cu")
		(at 271.180814 -321.549776 -90)
		(property "Reference" "C16"
			(at 0 0 90)
			(layer "B.SilkS")
			(hide yes)
			(effects
				(font
					(size 1.27 1.27)
				)
				(justify mirror)
			)
		)
		(property "Value" ""
			(at 0 0 90)
			(layer "B.Fab")
			(effects
				(font
					(size 1.27 1.27)
				)
				(justify mirror)
			)
		)
		(duplicate_pad_numbers_are_jumpers no)
		(fp_line
			(start -1.524 0.762)
			(end 1.524 0.762)
			(stroke
				(width 0.1524)
				(type default)
			)
			(layer "B.SilkS")
		)
		(fp_line
			(start 1.524 0.762)
			(end 1.524 -0.762)
			(stroke
				(width 0.1524)
				(type default)
			)
			(layer "B.SilkS")
		)
		(fp_line
			(start -1.524 -0.762)
			(end -1.524 0.762)
			(stroke
				(width 0.1524)
				(type default)
			)
			(layer "B.SilkS")
		)
		(fp_line
			(start 1.524 -0.762)
			(end -1.524 -0.762)
			(stroke
				(width 0.1524)
				(type default)
			)
			(layer "B.SilkS")
		)
		(fp_line
			(start -1.1049 0.724916)
			(end -1.1049 -0.724916)
			(stroke
				(width 0.1)
				(type default)
			)
			(layer "B.Fab")
		)
		(fp_line
			(start 1.1049 0.724916)
			(end -1.1049 0.724916)
			(stroke
				(width 0.1)
				(type default)
			)
			(layer "B.Fab")
		)
		(fp_line
			(start -1.1049 -0.724916)
			(end 1.1049 -0.724916)
			(stroke
				(width 0.1)
				(type default)
			)
			(layer "B.Fab")
		)
		(fp_line
			(start 1.1049 -0.724916)
			(end 1.1049 0.724916)
			(stroke
				(width 0.1)
				(type default)
			)
			(layer "B.Fab")
		)
		(pad "1" smd rect
			(at 0.889 0 270)
			(size 1.016 1.27)
			(layers "B.Cu" "B.Mask" "B.Paste")
			(net "P12V_S3_AUX_CPU0_NVDIMM")
		)
		(pad "2" smd rect
			(at -0.889 0 270)
			(size 1.016 1.27)
			(layers "B.Cu" "B.Mask" "B.Paste")
			(net "GND")
		)
	)
	(footprint ""
		(layer "B.Cu")
		(at 373.143018 -186.14517 -90)
		(property "Reference" "R911"
			(at 0 0 90)
			(layer "B.SilkS")
			(hide yes)
			(effects
				(font
					(size 1.27 1.27)
				)
				(justify mirror)
			)
		)
		(property "Value" ""
			(at 0 0 90)
			(layer "B.Fab")
			(effects
				(font
					(size 1.27 1.27)
				)
				(justify mirror)
			)
		)
		(duplicate_pad_numbers_are_jumpers no)
		(fp_line
			(start -0.7874 0.4064)
			(end 0.7874 0.4064)
			(stroke
				(width 0.1524)
				(type default)
			)
			(layer "B.SilkS")
		)
		(fp_line
			(start 0.7874 0.4064)
			(end 0.7874 -0.4064)
			(stroke
				(width 0.1524)
				(type default)
			)
			(layer "B.SilkS")
		)
		(fp_line
			(start -0.7874 -0.4064)
			(end -0.7874 0.4064)
			(stroke
				(width 0.1524)
				(type default)
			)
			(layer "B.SilkS")
		)
		(fp_line
			(start 0.7874 -0.4064)
			(end -0.7874 -0.4064)
			(stroke
				(width 0.1524)
				(type default)
			)
			(layer "B.SilkS")
		)
		(fp_line
			(start -0.67945 0.3048)
			(end -0.120396 0.3048)
			(stroke
				(width 0.1)
				(type default)
			)
			(layer "B.Fab")
		)
		(fp_line
			(start -0.120396 0.3048)
			(end -0.120396 0.2794)
			(stroke
				(width 0.1)
				(type default)
			)
			(layer "B.Fab")
		)
		(fp_line
			(start 0.12065 0.3048)
			(end 0.67945 0.3048)
			(stroke
				(width 0.1)
				(type default)
			)
			(layer "B.Fab")
		)
		(fp_line
			(start 0.67945 0.3048)
			(end 0.67945 -0.305054)
			(stroke
				(width 0.1)
				(type default)
			)
			(layer "B.Fab")
		)
		(fp_line
			(start -0.120396 0.2794)
			(end 0.12065 0.2794)
			(stroke
				(width 0.1)
				(type default)
			)
			(layer "B.Fab")
		)
		(fp_line
			(start 0.12065 0.2794)
			(end 0.12065 0.3048)
			(stroke
				(width 0.1)
				(type default)
			)
			(layer "B.Fab")
		)
		(fp_line
			(start -0.12065 -0.2794)
			(end -0.12065 -0.3048)
			(stroke
				(width 0.1)
				(type default)
			)
			(layer "B.Fab")
		)
		(fp_line
			(start 0.12065 -0.2794)
			(end -0.12065 -0.2794)
			(stroke
				(width 0.1)
				(type default)
			)
			(layer "B.Fab")
		)
		(fp_line
			(start -0.67945 -0.3048)
			(end -0.67945 0.3048)
			(stroke
				(width 0.1)
				(type default)
			)
			(layer "B.Fab")
		)
		(fp_line
			(start -0.12065 -0.3048)
			(end -0.67945 -0.3048)
			(stroke
				(width 0.1)
				(type default)
			)
			(layer "B.Fab")
		)
		(fp_line
			(start 0.12065 -0.305054)
			(end 0.12065 -0.2794)
			(stroke
				(width 0.1)
				(type default)
			)
			(layer "B.Fab")
		)
		(fp_line
			(start 0.67945 -0.305054)
			(end 0.12065 -0.305054)
			(stroke
				(width 0.1)
				(type default)
			)
			(layer "B.Fab")
		)
		(pad "1" smd circle
			(at 0.40005 0 90)
			(size 0 0)
			(layers "B.Cu" "B.Mask" "B.Paste")
			(net "PVNN_TERM_CPU0")
		)
		(pad "2" smd circle
			(at -0.40005 0 90)
			(size 0 0)
			(layers "B.Cu" "B.Mask" "B.Paste")
			(net "SMB_PEHPCPU0_GTL_R_SDA")
		)
	)
)
